# T6G (Grand Teton) — schematic netlist excerpt (pin names and nets, part order shuffled) for the footprints in the layout excerpt that follows; sources: Cadence DE-HDL packaged netlist, KiCad conversion of 04192023_DAF0TMB3IC0_F0TG_MB_C_brd_V02_OCP.brd

C9000  Q_CAP  1000PF 50V 5% EMPTY  pkg 0402  page 123 : A = PRSNT_CABLE_SWB_B1_ISO_N ; B = GND
C6573  Q_CAP_DIFFBUS  DIFF BUS_0.22UF 6.3V 20% X6S  pkg C0201  page 297 : \1\ = P5E_CPU0_P2_TX_BUF_C_DP<4> ; \2\ = P5E_CPU0_P2_TX_BUF_DP<4>
R1477  Q_RES  4.7K 5% EMPTY  pkg 0201LF  page 298 : A = P1V8_CPU0_RT_1D ; B = JTAG_TMS_RT_CPU0_P2

(kicad_pcb
	(version 20260206)
	(generator "pcbnew")
	(generator_version "10.0")
	(general
		(thickness 1.6)
		(legacy_teardrops no)
	)
	(paper "A4")
	(title_block
		(title "04192023_DAF0TMB3IC0_F0TG_MB_C_brd_V02_OCP.brd")
		(comment 1 "Grand Teton / footprints 2656-2658 of 8354")
	)
	(layers
		(0 "F.Cu" signal "TOP")
		(4 "In1.Cu" signal "GND")
		(6 "In2.Cu" signal "IN1")
		(8 "In3.Cu" signal "GND1")
		(10 "In4.Cu" signal "IN2")
		(12 "In5.Cu" signal "GND2")
		(14 "In6.Cu" signal "IN3")
		(16 "In7.Cu" signal "GND3")
		(18 "In8.Cu" signal "VCC")
		(20 "In9.Cu" signal "VCC1")
		(22 "In10.Cu" signal "GND4")
		(24 "In11.Cu" signal "IN4")
		(26 "In12.Cu" signal "GND5")
		(28 "In13.Cu" signal "IN5")
		(30 "In14.Cu" signal "GND6")
		(32 "In15.Cu" signal "IN6")
		(34 "In16.Cu" signal "GND7")
		(2 "B.Cu" signal "BOTTOM")
		(9 "F.Adhes" user "F.Adhesive")
		(11 "B.Adhes" user "B.Adhesive")
		(13 "F.Paste" user "Package Geometry/Pastemask Top")
		(15 "B.Paste" user "Package Geometry/Pastemask Bottom")
		(5 "F.SilkS" user "Ref Des/Silkscreen Top")
		(7 "B.SilkS" user "Ref Des/Silkscreen Bottom")
		(1 "F.Mask" user "Board Geometry/Soldermask Top")
		(3 "B.Mask" user "Board Geometry/Soldermask Bottom")
		(17 "Dwgs.User" user "User.Drawings")
		(19 "Cmts.User" user "User.Comments")
		(21 "Eco1.User" user "User.Eco1")
		(23 "Eco2.User" user "User.Eco2")
		(25 "Edge.Cuts" user "Board Geometry/Outline")
		(27 "Margin" user)
		(31 "F.CrtYd" user "Package Geometry/Place Bound Top")
		(29 "B.CrtYd" user "Package Geometry/Place Bound Bottom")
		(35 "F.Fab" user "Ref Des/Assembly Top")
		(33 "B.Fab" user "Ref Des/Assembly Bottom")
	)
	(footprint ""
		(layer "F.Cu")
		(at 384.036062 -416.899344 -90)
		(property "Reference" "C6573"
			(at 0 0 270)
			(layer "F.SilkS")
			(hide yes)
			(effects
				(font
					(size 1.27 1.27)
				)
			)
		)
		(property "Value" ""
			(at 0 0 270)
			(layer "F.Fab")
			(effects
				(font
					(size 1.27 1.27)
				)
			)
		)
		(duplicate_pad_numbers_are_jumpers no)
		(fp_line
			(start -0.299974 0.150114)
			(end -0.299974 -0.150114)
			(stroke
				(width 0.1)
				(type default)
			)
			(layer "F.Fab")
		)
		(fp_line
			(start 0.299974 0.150114)
			(end -0.299974 0.150114)
			(stroke
				(width 0.1)
				(type default)
			)
			(layer "F.Fab")
		)
		(fp_line
			(start -0.299974 -0.150114)
			(end 0.299974 -0.150114)
			(stroke
				(width 0.1)
				(type default)
			)
			(layer "F.Fab")
		)
		(fp_line
			(start 0.299974 -0.150114)
			(end 0.299974 0.150114)
			(stroke
				(width 0.1)
				(type default)
			)
			(layer "F.Fab")
		)
		(pad "1" smd rect
			(at -0.2667 0 270)
			(size 0.3048 0.381)
			(layers "F.Cu" "F.Mask" "F.Paste")
			(net "P5E_CPU0_P2_TX_BUF_C_DP<4>")
		)
		(pad "2" smd rect
			(at 0.2667 0 270)
			(size 0.3048 0.381)
			(layers "F.Cu" "F.Mask" "F.Paste")
			(net "P5E_CPU0_P2_TX_BUF_DP<4>")
		)
	)
	(footprint ""
		(layer "F.Cu")
		(at 432.308 -405.13)
		(property "Reference" "R1477"
			(at 0 0 0)
			(layer "F.SilkS")
			(hide yes)
			(effects
				(font
					(size 1.27 1.27)
				)
			)
		)
		(property "Value" ""
			(at 0 0 0)
			(layer "F.Fab")
			(effects
				(font
					(size 1.27 1.27)
				)
			)
		)
		(duplicate_pad_numbers_are_jumpers no)
		(fp_line
			(start -0.32512 -0.175006)
			(end 0.32512 -0.175006)
			(stroke
				(width 0.1)
				(type default)
			)
			(layer "F.Fab")
		)
		(fp_line
			(start -0.32512 0.175006)
			(end -0.32512 -0.175006)
			(stroke
				(width 0.1)
				(type default)
			)
			(layer "F.Fab")
		)
		(fp_line
			(start 0.32512 -0.175006)
			(end 0.32512 0.175006)
			(stroke
				(width 0.1)
				(type default)
			)
			(layer "F.Fab")
		)
		(fp_line
			(start 0.32512 0.175006)
			(end -0.32512 0.175006)
			(stroke
				(width 0.1)
				(type default)
			)
			(layer "F.Fab")
		)
		(pad "1" smd rect
			(at -0.2667 0)
			(size 0.3048 0.381)
			(layers "F.Cu" "F.Mask" "F.Paste")
			(net "P1V8_CPU0_RT_1D")
		)
		(pad "2" smd rect
			(at 0.2667 0 180)
			(size 0.3048 0.381)
			(layers "F.Cu" "F.Mask" "F.Paste")
			(net "JTAG_TMS_RT_CPU0_P2")
		)
	)
	(footprint ""
		(layer "F.Cu")
		(at 364.362238 -412.370016 180)
		(property "Reference" "C9000"
			(at 0 0 180)
			(layer "F.SilkS")
			(hide yes)
			(effects
				(font
					(size 1.27 1.27)
				)
			)
		)
		(property "Value" ""
			(at 0 0 180)
			(layer "F.Fab")
			(effects
				(font
					(size 1.27 1.27)
				)
			)
		)
		(duplicate_pad_numbers_are_jumpers no)
		(fp_line
			(start 0.7874 0.4064)
			(end -0.7874 0.4064)
			(stroke
				(width 0.1524)
				(type default)
			)
			(layer "F.SilkS")
		)
		(fp_line
			(start 0.7874 -0.4064)
			(end 0.7874 0.4064)
			(stroke
				(width 0.1524)
				(type default)
			)
			(layer "F.SilkS")
		)
		(fp_line
			(start -0.7874 0.4064)
			(end -0.7874 -0.4064)
			(stroke
				(width 0.1524)
				(type default)
			)
			(layer "F.SilkS")
		)
		(fp_line
			(start -0.7874 -0.4064)
			(end 0.7874 -0.4064)
			(stroke
				(width 0.1524)
				(type default)
			)
			(layer "F.SilkS")
		)
		(fp_line
			(start 0.67945 0.3048)
			(end 0.120396 0.3048)
			(stroke
				(width 0.1)
				(type default)
			)
			(layer "F.Fab")
		)
		(fp_line
			(start 0.67945 -0.3048)
			(end 0.67945 0.3048)
			(stroke
				(width 0.1)
				(type default)
			)
			(layer "F.Fab")
		)
		(fp_line
			(start 0.12065 -0.2794)
			(end 0.12065 -0.3048)
			(stroke
				(width 0.1)
				(type default)
			)
			(layer "F.Fab")
		)
		(fp_line
			(start 0.12065 -0.3048)
			(end 0.67945 -0.3048)
			(stroke
				(width 0.1)
				(type default)
			)
			(layer "F.Fab")
		)
		(fp_line
			(start 0.120396 0.3048)
			(end 0.120396 0.2794)
			(stroke
				(width 0.1)
				(type default)
			)
			(layer "F.Fab")
		)
		(fp_line
			(start 0.120396 0.2794)
			(end -0.12065 0.2794)
			(stroke
				(width 0.1)
				(type default)
			)
			(layer "F.Fab")
		)
		(fp_line
			(start -0.12065 0.3048)
			(end -0.67945 0.3048)
			(stroke
				(width 0.1)
				(type default)
			)
			(layer "F.Fab")
		)
		(fp_line
			(start -0.12065 0.2794)
			(end -0.12065 0.3048)
			(stroke
				(width 0.1)
				(type default)
			)
			(layer "F.Fab")
		)
		(fp_line
			(start -0.12065 -0.2794)
			(end 0.12065 -0.2794)
			(stroke
				(width 0.1)
				(type default)
			)
			(layer "F.Fab")
		)
		(fp_line
			(start -0.12065 -0.305054)
			(end -0.12065 -0.2794)
			(stroke
				(width 0.1)
				(type default)
			)
			(layer "F.Fab")
		)
		(fp_line
			(start -0.67945 0.3048)
			(end -0.67945 -0.305054)
			(stroke
				(width 0.1)
				(type default)
			)
			(layer "F.Fab")
		)
		(fp_line
			(start -0.67945 -0.305054)
			(end -0.12065 -0.305054)
			(stroke
				(width 0.1)
				(type default)
			)
			(layer "F.Fab")
		)
		(pad "1" smd circle
			(at -0.40005 0 180)
			(size 0 0)
			(layers "F.Cu" "F.Mask" "F.Paste")
			(net "PRSNT_CABLE_SWB_B1_ISO_N")
		)
		(pad "2" smd circle
			(at 0.40005 0 180)
			(size 0 0)
			(layers "F.Cu" "F.Mask" "F.Paste")
			(net "GND")
		)
	)
)
